(kicad_pcb
	(version 20260206)
	(generator "pcbnew")
	(generator_version "10.0")
	(general
		(thickness 1.6)
		(legacy_teardrops no)
	)
	(paper "A4")
	(title_block
		(title "peb — Lightning_PEB_BRD.brd")
		(comment 1 "Lightning (Wiwynn / Facebook NVMe JBOF) / footprints 1482-1488 of 2563")
	)
	(layers
		(0 "F.Cu" signal "TOP")
		(4 "In1.Cu" signal "L2GND")
		(6 "In2.Cu" signal "L3")
		(8 "In3.Cu" signal "L4VCC")
		(10 "In4.Cu" signal "L5VCC")
		(12 "In5.Cu" signal "L6")
		(14 "In6.Cu" signal "L7GND")
		(2 "B.Cu" signal "BOTTOM")
		(9 "F.Adhes" user "F.Adhesive")
		(11 "B.Adhes" user "B.Adhesive")
		(13 "F.Paste" user "Package Geometry/Pastemask Top")
		(15 "B.Paste" user "Package Geometry/Pastemask Bottom")
		(5 "F.SilkS" user "Ref Des/Silkscreen Top")
		(7 "B.SilkS" user "Ref Des/Silkscreen Bottom")
		(1 "F.Mask" user "Board Geometry/Soldermask Top")
		(3 "B.Mask" user "Board Geometry/Soldermask Bottom")
		(17 "Dwgs.User" user "User.Drawings")
		(19 "Cmts.User" user "User.Comments")
		(21 "Eco1.User" user "User.Eco1")
		(23 "Eco2.User" user "User.Eco2")
		(25 "Edge.Cuts" user "Board Geometry/Outline")
		(27 "Margin" user)
		(31 "F.CrtYd" user "Package Geometry/Place Bound Top")
		(29 "B.CrtYd" user "Package Geometry/Place Bound Bottom")
		(35 "F.Fab" user "Ref Des/Assembly Top")
		(33 "B.Fab" user "Ref Des/Assembly Bottom")
	)
	(footprint ""
		(layer "F.Cu")
		(at 36.1442 -77.8256 90)
		(property "Reference" "PC71"
			(at 0 0 90)
			(layer "F.SilkS")
			(hide yes)
			(effects
				(font
					(size 1.27 1.27)
				)
			)
		)
		(property "Value" "SCD1U50V3KX-GP"
			(at 0 -2.8194 90)
			(unlocked yes)
			(layer "F.Fab")
			(hide yes)
			(effects
				(font
					(size 1.016 1.016)
					(thickness 0.1524)
				)
			)
		)
		(property "Device Type" "C603H36"
			(at 0 -4.3434 90)
			(unlocked yes)
			(layer "F.Fab")
			(hide yes)
			(effects
				(font
					(size 1.016 1.016)
					(thickness 0.1524)
				)
			)
		)
		(duplicate_pad_numbers_are_jumpers no)
		(fp_line
			(start 0.508 0)
			(end -0.508 0)
			(stroke
				(width 0.2032)
				(type default)
			)
			(layer "F.SilkS")
		)
		(fp_rect
			(start -0.5842 1.3335)
			(end 0.5842 -1.3335)
			(stroke
				(width 0)
				(type default)
			)
			(fill no)
			(layer "F.CrtYd")
		)
		(fp_rect
			(start -0.5842 1.3335)
			(end 0.5842 -1.3335)
			(stroke
				(width 0)
				(type default)
			)
			(fill no)
			(layer "F.Fab")
		)
		(pad "1" smd custom
			(at 0 -0.762 90)
			(size 0.2159 0.2159)
			(layers "F.Cu" "F.Mask" "F.Paste")
			(net "P5V_STBY_BS_RC")
			(options
				(clearance outline)
				(anchor circle)
			)
			(primitives
				(gr_poly
					(pts
						(arc
							(start -0.3302 -0.4318)
							(mid -0.402042 -0.402042)
							(end -0.4318 -0.3302)
						)
						(arc
							(start -0.4318 0.3302)
							(mid -0.402042 0.402042)
							(end -0.3302 0.4318)
						)
						(arc
							(start 0.3302 0.4318)
							(mid 0.402042 0.402042)
							(end 0.4318 0.3302)
						)
						(arc
							(start 0.4318 -0.3302)
							(mid 0.402042 -0.402042)
							(end 0.3302 -0.4318)
						)
					)
					(width 0)
					(fill yes)
				)
			)
		)
		(pad "2" smd custom
			(at 0 0.762 90)
			(size 0.2159 0.2159)
			(layers "F.Cu" "F.Mask" "F.Paste")
			(net "P5V_STBY_LX")
			(options
				(clearance outline)
				(anchor circle)
			)
			(primitives
				(gr_poly
					(pts
						(arc
							(start -0.3302 -0.4318)
							(mid -0.402042 -0.402042)
							(end -0.4318 -0.3302)
						)
						(arc
							(start -0.4318 0.3302)
							(mid -0.402042 0.402042)
							(end -0.3302 0.4318)
						)
						(arc
							(start 0.3302 0.4318)
							(mid 0.402042 0.402042)
							(end 0.4318 0.3302)
						)
						(arc
							(start 0.4318 -0.3302)
							(mid 0.402042 -0.402042)
							(end 0.3302 -0.4318)
						)
					)
					(width 0)
					(fill yes)
				)
			)
		)
	)
	(footprint ""
		(layer "F.Cu")
		(at 155.921202 -54.256432 -90)
		(property "Reference" "PR179"
			(at 0 0 270)
			(layer "F.SilkS")
			(hide yes)
			(effects
				(font
					(size 1.27 1.27)
				)
			)
		)
		(property "Value" "10KR2F-2-GP"
			(at 0.064008 -3.993896 270)
			(unlocked yes)
			(layer "F.Fab")
			(hide yes)
			(effects
				(font
					(size 1.016 1.016)
					(thickness 0.1524)
				)
			)
		)
		(property "Device Type" "R402H16"
			(at 0.064008 -5.517896 270)
			(unlocked yes)
			(layer "F.Fab")
			(hide yes)
			(effects
				(font
					(size 1.016 1.016)
					(thickness 0.1524)
				)
			)
		)
		(duplicate_pad_numbers_are_jumpers no)
		(fp_line
			(start -0.508 -0.9398)
			(end -0.508 0.9398)
			(stroke
				(width 0.1524)
				(type default)
			)
			(layer "F.SilkS")
		)
		(fp_line
			(start 0.508 -0.9398)
			(end -0.508 -0.9398)
			(stroke
				(width 0.1524)
				(type default)
			)
			(layer "F.SilkS")
		)
		(fp_rect
			(start -0.508 0.9398)
			(end 0.508 -0.9398)
			(stroke
				(width 0)
				(type default)
			)
			(fill no)
			(layer "F.CrtYd")
		)
		(fp_rect
			(start -0.508 0.9398)
			(end 0.508 -0.9398)
			(stroke
				(width 0)
				(type default)
			)
			(fill no)
			(layer "F.Fab")
		)
		(pad "1" smd custom
			(at 0 -0.4445 270)
			(size 0.1397 0.1397)
			(layers "F.Cu" "F.Mask" "F.Paste")
			(net "P0V9_VFB")
			(options
				(clearance outline)
				(anchor circle)
			)
			(primitives
				(gr_poly
					(pts
						(arc
							(start -0.1778 -0.2794)
							(mid -0.249642 -0.249642)
							(end -0.2794 -0.1778)
						)
						(arc
							(start -0.2794 0.1778)
							(mid -0.249642 0.249642)
							(end -0.1778 0.2794)
						)
						(arc
							(start 0.1778 0.2794)
							(mid 0.249642 0.249642)
							(end 0.2794 0.1778)
						)
						(arc
							(start 0.2794 -0.1778)
							(mid 0.249642 -0.249642)
							(end 0.1778 -0.2794)
						)
					)
					(width 0)
					(fill yes)
				)
			)
		)
		(pad "2" smd custom
			(at 0 0.4445 270)
			(size 0.1397 0.1397)
			(layers "F.Cu" "F.Mask" "F.Paste")
			(net "AGND_P0V9")
			(options
				(clearance outline)
				(anchor circle)
			)
			(primitives
				(gr_poly
					(pts
						(arc
							(start -0.1778 -0.2794)
							(mid -0.249642 -0.249642)
							(end -0.2794 -0.1778)
						)
						(arc
							(start -0.2794 0.1778)
							(mid -0.249642 0.249642)
							(end -0.1778 0.2794)
						)
						(arc
							(start 0.1778 0.2794)
							(mid 0.249642 0.249642)
							(end 0.2794 0.1778)
						)
						(arc
							(start 0.2794 -0.1778)
							(mid 0.249642 -0.249642)
							(end 0.1778 -0.2794)
						)
					)
					(width 0)
					(fill yes)
				)
			)
		)
	)
	(footprint ""
		(layer "F.Cu")
		(at 29.337 -116.713 180)
		(property "Reference" "R237"
			(at 0 0 180)
			(layer "F.SilkS")
			(hide yes)
			(effects
				(font
					(size 1.27 1.27)
				)
			)
		)
		(property "Value" "100KR2F-L1-GP"
			(at 0.064008 -3.993896 180)
			(unlocked yes)
			(layer "F.Fab")
			(hide yes)
			(effects
				(font
					(size 1.016 1.016)
					(thickness 0.1524)
				)
			)
		)
		(property "Device Type" "R402H16"
			(at 0.064008 -5.517896 180)
			(unlocked yes)
			(layer "F.Fab")
			(hide yes)
			(effects
				(font
					(size 1.016 1.016)
					(thickness 0.1524)
				)
			)
		)
		(duplicate_pad_numbers_are_jumpers no)
		(fp_line
			(start 0.508 -0.9398)
			(end -0.508 -0.9398)
			(stroke
				(width 0.1524)
				(type default)
			)
			(layer "F.SilkS")
		)
		(fp_line
			(start -0.508 -0.9398)
			(end -0.508 0.9398)
			(stroke
				(width 0.1524)
				(type default)
			)
			(layer "F.SilkS")
		)
		(fp_rect
			(start -0.508 0.9398)
			(end 0.508 -0.9398)
			(stroke
				(width 0)
				(type default)
			)
			(fill no)
			(layer "F.CrtYd")
		)
		(fp_rect
			(start -0.508 0.9398)
			(end 0.508 -0.9398)
			(stroke
				(width 0)
				(type default)
			)
			(fill no)
			(layer "F.Fab")
		)
		(pad "1" smd custom
			(at 0 -0.4445 180)
			(size 0.1397 0.1397)
			(layers "F.Cu" "F.Mask" "F.Paste")
			(net "GND")
			(options
				(clearance outline)
				(anchor circle)
			)
			(primitives
				(gr_poly
					(pts
						(arc
							(start -0.1778 -0.2794)
							(mid -0.249642 -0.249642)
							(end -0.2794 -0.1778)
						)
						(arc
							(start -0.2794 0.1778)
							(mid -0.249642 0.249642)
							(end -0.1778 0.2794)
						)
						(arc
							(start 0.1778 0.2794)
							(mid 0.249642 0.249642)
							(end 0.2794 0.1778)
						)
						(arc
							(start 0.2794 -0.1778)
							(mid 0.249642 -0.249642)
							(end 0.1778 -0.2794)
						)
					)
					(width 0)
					(fill yes)
				)
			)
		)
		(pad "2" smd custom
			(at 0 0.4445 180)
			(size 0.1397 0.1397)
			(layers "F.Cu" "F.Mask" "F.Paste")
			(net "TP_BMC0_LPC_LAD3")
			(options
				(clearance outline)
				(anchor circle)
			)
			(primitives
				(gr_poly
					(pts
						(arc
							(start -0.1778 -0.2794)
							(mid -0.249642 -0.249642)
							(end -0.2794 -0.1778)
						)
						(arc
							(start -0.2794 0.1778)
							(mid -0.249642 0.249642)
							(end -0.1778 0.2794)
						)
						(arc
							(start 0.1778 0.2794)
							(mid 0.249642 0.249642)
							(end 0.2794 0.1778)
						)
						(arc
							(start 0.2794 -0.1778)
							(mid 0.249642 -0.249642)
							(end 0.1778 -0.2794)
						)
					)
					(width 0)
					(fill yes)
				)
			)
		)
	)
	(footprint ""
		(layer "F.Cu")
		(at 17.2974 -66.6242 180)
		(property "Reference" "R474"
			(at 0 0 180)
			(layer "F.SilkS")
			(hide yes)
			(effects
				(font
					(size 1.27 1.27)
				)
			)
		)
		(property "Value" "0R3J-0-U-GP"
			(at -0.0254 -2.5146 180)
			(unlocked yes)
			(layer "F.Fab")
			(hide yes)
			(effects
				(font
					(size 1.016 1.016)
					(thickness 0.1524)
				)
			)
		)
		(property "Device Type" "R603H22"
			(at -0.0254 -4.0386 180)
			(unlocked yes)
			(layer "F.Fab")
			(hide yes)
			(effects
				(font
					(size 1.016 1.016)
					(thickness 0.1524)
				)
			)
		)
		(duplicate_pad_numbers_are_jumpers no)
		(fp_line
			(start 0.2032 0)
			(end 0.4826 0)
			(stroke
				(width 0.2032)
				(type default)
			)
			(layer "F.SilkS")
		)
		(fp_line
			(start -0.4826 0)
			(end -0.2032 0)
			(stroke
				(width 0.2032)
				(type default)
			)
			(layer "F.SilkS")
		)
		(fp_rect
			(start -0.5842 1.3335)
			(end 0.5842 -1.3335)
			(stroke
				(width 0)
				(type default)
			)
			(fill no)
			(layer "F.CrtYd")
		)
		(fp_rect
			(start -0.5842 1.3335)
			(end 0.5842 -1.3335)
			(stroke
				(width 0)
				(type default)
			)
			(fill no)
			(layer "F.Fab")
		)
		(pad "1" smd custom
			(at 0 -0.762 180)
			(size 0.2159 0.2159)
			(layers "F.Cu" "F.Mask" "F.Paste")
			(net "P1V5_I210")
			(options
				(clearance outline)
				(anchor circle)
			)
			(primitives
				(gr_poly
					(pts
						(arc
							(start -0.3302 -0.4318)
							(mid -0.402042 -0.402042)
							(end -0.4318 -0.3302)
						)
						(arc
							(start -0.4318 0.3302)
							(mid -0.402042 0.402042)
							(end -0.3302 0.4318)
						)
						(arc
							(start 0.3302 0.4318)
							(mid 0.402042 0.402042)
							(end 0.4318 0.3302)
						)
						(arc
							(start 0.4318 -0.3302)
							(mid 0.402042 -0.402042)
							(end 0.3302 -0.4318)
						)
					)
					(width 0)
					(fill yes)
				)
			)
		)
		(pad "2" smd custom
			(at 0 0.762 180)
			(size 0.2159 0.2159)
			(layers "F.Cu" "F.Mask" "F.Paste")
			(net "LAN1_56")
			(options
				(clearance outline)
				(anchor circle)
			)
			(primitives
				(gr_poly
					(pts
						(arc
							(start -0.3302 -0.4318)
							(mid -0.402042 -0.402042)
							(end -0.4318 -0.3302)
						)
						(arc
							(start -0.4318 0.3302)
							(mid -0.402042 0.402042)
							(end -0.3302 0.4318)
						)
						(arc
							(start 0.3302 0.4318)
							(mid 0.402042 0.402042)
							(end 0.4318 0.3302)
						)
						(arc
							(start 0.4318 -0.3302)
							(mid 0.402042 -0.402042)
							(end 0.3302 -0.4318)
						)
					)
					(width 0)
					(fill yes)
				)
			)
		)
	)
	(footprint ""
		(layer "F.Cu")
		(at 28.956 -98.7044 -90)
		(property "Reference" "R2943"
			(at 0 0 270)
			(layer "F.SilkS")
			(hide yes)
			(effects
				(font
					(size 1.27 1.27)
				)
			)
		)
		(property "Value" "10KR2F-2-GP"
			(at 0.064008 -3.993896 270)
			(unlocked yes)
			(layer "F.Fab")
			(hide yes)
			(effects
				(font
					(size 1.016 1.016)
					(thickness 0.1524)
				)
			)
		)
		(property "Device Type" "R402H16"
			(at 0.064008 -5.517896 270)
			(unlocked yes)
			(layer "F.Fab")
			(hide yes)
			(effects
				(font
					(size 1.016 1.016)
					(thickness 0.1524)
				)
			)
		)
		(duplicate_pad_numbers_are_jumpers no)
		(fp_line
			(start -0.508 -0.9398)
			(end -0.508 0.9398)
			(stroke
				(width 0.1524)
				(type default)
			)
			(layer "F.SilkS")
		)
		(fp_line
			(start 0.508 -0.9398)
			(end -0.508 -0.9398)
			(stroke
				(width 0.1524)
				(type default)
			)
			(layer "F.SilkS")
		)
		(fp_rect
			(start -0.508 0.9398)
			(end 0.508 -0.9398)
			(stroke
				(width 0)
				(type default)
			)
			(fill no)
			(layer "F.CrtYd")
		)
		(fp_rect
			(start -0.508 0.9398)
			(end 0.508 -0.9398)
			(stroke
				(width 0)
				(type default)
			)
			(fill no)
			(layer "F.Fab")
		)
		(pad "1" smd custom
			(at 0 -0.4445 270)
			(size 0.1397 0.1397)
			(layers "F.Cu" "F.Mask" "F.Paste")
			(net "P3V3_STBY")
			(options
				(clearance outline)
				(anchor circle)
			)
			(primitives
				(gr_poly
					(pts
						(arc
							(start -0.1778 -0.2794)
							(mid -0.249642 -0.249642)
							(end -0.2794 -0.1778)
						)
						(arc
							(start -0.2794 0.1778)
							(mid -0.249642 0.249642)
							(end -0.1778 0.2794)
						)
						(arc
							(start 0.1778 0.2794)
							(mid 0.249642 0.249642)
							(end 0.2794 0.1778)
						)
						(arc
							(start 0.2794 -0.1778)
							(mid 0.249642 -0.249642)
							(end 0.1778 -0.2794)
						)
					)
					(width 0)
					(fill yes)
				)
			)
		)
		(pad "2" smd custom
			(at 0 0.4445 270)
			(size 0.1397 0.1397)
			(layers "F.Cu" "F.Mask" "F.Paste")
			(net "FM_TPM_PRES_RST")
			(options
				(clearance outline)
				(anchor circle)
			)
			(primitives
				(gr_poly
					(pts
						(arc
							(start -0.1778 -0.2794)
							(mid -0.249642 -0.249642)
							(end -0.2794 -0.1778)
						)
						(arc
							(start -0.2794 0.1778)
							(mid -0.249642 0.249642)
							(end -0.1778 0.2794)
						)
						(arc
							(start 0.1778 0.2794)
							(mid 0.249642 0.249642)
							(end 0.2794 0.1778)
						)
						(arc
							(start 0.2794 -0.1778)
							(mid 0.249642 -0.249642)
							(end 0.1778 -0.2794)
						)
					)
					(width 0)
					(fill yes)
				)
			)
		)
	)
	(footprint ""
		(layer "F.Cu")
		(at 117.03939 -37.975286 180)
		(property "Reference" "Q25"
			(at 0 0 180)
			(layer "F.SilkS")
			(hide yes)
			(effects
				(font
					(size 1.27 1.27)
				)
			)
		)
		(property "Value" "2N7002K-1-GP"
			(at 0.127 -8.9662 180)
			(unlocked yes)
			(layer "F.Fab")
			(hide yes)
			(effects
				(font
					(size 1.016 1.016)
					(thickness 0.1524)
				)
			)
		)
		(property "Device Type" "SOT23DGS2D4H44"
			(at 0.127 -10.4902 180)
			(unlocked yes)
			(layer "F.Fab")
			(hide yes)
			(effects
				(font
					(size 1.016 1.016)
					(thickness 0.1524)
				)
			)
		)
		(duplicate_pad_numbers_are_jumpers no)
		(fp_line
			(start 1.651 1.778)
			(end 1.651 -1.778)
			(stroke
				(width 0.1524)
				(type default)
			)
			(layer "F.SilkS")
		)
		(fp_line
			(start 1.651 -1.778)
			(end -1.651 -1.778)
			(stroke
				(width 0.1524)
				(type default)
			)
			(layer "F.SilkS")
		)
		(fp_line
			(start -1.651 1.778)
			(end 1.651 1.778)
			(stroke
				(width 0.1524)
				(type default)
			)
			(layer "F.SilkS")
		)
		(fp_line
			(start -1.651 -1.778)
			(end -1.651 1.778)
			(stroke
				(width 0.1524)
				(type default)
			)
			(layer "F.SilkS")
		)
		(fp_poly
			(pts
				(xy -1.778 1.8796) (xy -1.778 -1.8796) (xy 1.778 -1.8796) (xy 1.778 1.8796)
			)
			(stroke
				(width 0)
				(type default)
			)
			(fill no)
			(layer "F.CrtYd")
		)
		(fp_poly
			(pts
				(xy -1.778 1.8796) (xy -1.778 -1.8796) (xy 1.778 -1.8796) (xy 1.778 1.8796)
			)
			(stroke
				(width 0)
				(type default)
			)
			(fill no)
			(layer "F.Fab")
		)
		(pad "D" smd custom
			(at 0 -0.9525 180)
			(size 0.1905 0.1905)
			(layers "F.Cu" "F.Mask" "F.Paste")
			(net "LED_Q_2")
			(options
				(clearance outline)
				(anchor circle)
			)
			(primitives
				(gr_poly
					(pts
						(arc
							(start -0.1778 0.5715)
							(mid -0.321484 0.511984)
							(end -0.381 0.3683)
						)
						(arc
							(start -0.381 -0.3683)
							(mid -0.321484 -0.511984)
							(end -0.1778 -0.5715)
						)
						(arc
							(start 0.1778 -0.5715)
							(mid 0.321484 -0.511984)
							(end 0.381 -0.3683)
						)
						(arc
							(start 0.381 0.3683)
							(mid 0.321484 0.511984)
							(end 0.1778 0.5715)
						)
					)
					(width 0)
					(fill yes)
				)
			)
		)
		(pad "G" smd custom
			(at -0.98425 0.9525 180)
			(size 0.1905 0.1905)
			(layers "F.Cu" "F.Mask" "F.Paste")
			(net "UPLINK2_R")
			(options
				(clearance outline)
				(anchor circle)
			)
			(primitives
				(gr_poly
					(pts
						(arc
							(start -0.1778 0.5715)
							(mid -0.321484 0.511984)
							(end -0.381 0.3683)
						)
						(arc
							(start -0.381 -0.3683)
							(mid -0.321484 -0.511984)
							(end -0.1778 -0.5715)
						)
						(arc
							(start 0.1778 -0.5715)
							(mid 0.321484 -0.511984)
							(end 0.381 -0.3683)
						)
						(arc
							(start 0.381 0.3683)
							(mid 0.321484 0.511984)
							(end 0.1778 0.5715)
						)
					)
					(width 0)
					(fill yes)
				)
			)
		)
		(pad "S" smd custom
			(at 0.98425 0.9525 180)
			(size 0.1905 0.1905)
			(layers "F.Cu" "F.Mask" "F.Paste")
			(net "GND")
			(options
				(clearance outline)
				(anchor circle)
			)
			(primitives
				(gr_poly
					(pts
						(arc
							(start -0.1778 0.5715)
							(mid -0.321484 0.511984)
							(end -0.381 0.3683)
						)
						(arc
							(start -0.381 -0.3683)
							(mid -0.321484 -0.511984)
							(end -0.1778 -0.5715)
						)
						(arc
							(start 0.1778 -0.5715)
							(mid 0.321484 -0.511984)
							(end 0.381 -0.3683)
						)
						(arc
							(start 0.381 0.3683)
							(mid 0.321484 0.511984)
							(end 0.1778 0.5715)
						)
					)
					(width 0)
					(fill yes)
				)
			)
		)
	)
	(footprint ""
		(layer "F.Cu")
		(at 56.126126 -110.914688)
		(property "Reference" "R328"
			(at 0 0 0)
			(layer "F.SilkS")
			(hide yes)
			(effects
				(font
					(size 1.27 1.27)
				)
			)
		)
		(property "Value" "4K7R2F-GP"
			(at 0.064008 -3.993896 0)
			(unlocked yes)
			(layer "F.Fab")
			(hide yes)
			(effects
				(font
					(size 1.016 1.016)
					(thickness 0.1524)
				)
			)
		)
		(property "Device Type" "R402H16"
			(at 0.064008 -5.517896 0)
			(unlocked yes)
			(layer "F.Fab")
			(hide yes)
			(effects
				(font
					(size 1.016 1.016)
					(thickness 0.1524)
				)
			)
		)
		(duplicate_pad_numbers_are_jumpers no)
		(fp_line
			(start -0.508 -0.9398)
			(end -0.508 0.9398)
			(stroke
				(width 0.1524)
				(type default)
			)
			(layer "F.SilkS")
		)
		(fp_line
			(start 0.508 -0.9398)
			(end -0.508 -0.9398)
			(stroke
				(width 0.1524)
				(type default)
			)
			(layer "F.SilkS")
		)
		(fp_rect
			(start -0.508 0.9398)
			(end 0.508 -0.9398)
			(stroke
				(width 0)
				(type default)
			)
			(fill no)
			(layer "F.CrtYd")
		)
		(fp_rect
			(start -0.508 0.9398)
			(end 0.508 -0.9398)
			(stroke
				(width 0)
				(type default)
			)
			(fill no)
			(layer "F.Fab")
		)
		(pad "1" smd custom
			(at 0 -0.4445)
			(size 0.1397 0.1397)
			(layers "F.Cu" "F.Mask" "F.Paste")
			(net "P3V3_STBY")
			(options
				(clearance outline)
				(anchor circle)
			)
			(primitives
				(gr_poly
					(pts
						(arc
							(start -0.1778 -0.2794)
							(mid -0.249642 -0.249642)
							(end -0.2794 -0.1778)
						)
						(arc
							(start -0.2794 0.1778)
							(mid -0.249642 0.249642)
							(end -0.1778 0.2794)
						)
						(arc
							(start 0.1778 0.2794)
							(mid 0.249642 0.249642)
							(end 0.2794 0.1778)
						)
						(arc
							(start 0.2794 -0.1778)
							(mid 0.249642 -0.249642)
							(end 0.1778 -0.2794)
						)
					)
					(width 0)
					(fill yes)
				)
			)
		)
		(pad "2" smd custom
			(at 0 0.4445)
			(size 0.1397 0.1397)
			(layers "F.Cu" "F.Mask" "F.Paste")
			(net "I2C7_LS_G2")
			(options
				(clearance outline)
				(anchor circle)
			)
			(primitives
				(gr_poly
					(pts
						(arc
							(start -0.1778 -0.2794)
							(mid -0.249642 -0.249642)
							(end -0.2794 -0.1778)
						)
						(arc
							(start -0.2794 0.1778)
							(mid -0.249642 0.249642)
							(end -0.1778 0.2794)
						)
						(arc
							(start 0.1778 0.2794)
							(mid 0.249642 0.249642)
							(end 0.2794 0.1778)
						)
						(arc
							(start 0.2794 -0.1778)
							(mid 0.249642 -0.249642)
							(end 0.1778 -0.2794)
						)
					)
					(width 0)
					(fill yes)
				)
			)
		)
	)
)
